(kicad_pcb
	(version 20260206)
	(generator "pcbnew")
	(generator_version "10.0")
	(general
		(thickness 1.6)
		(legacy_teardrops no)
	)
	(paper "A4")
	(title_block
		(title "Bryce Canyon_F.DPB_16315-1-OCP.brd")
		(comment 1 "Bryce Canyon / footprints 1812-1818 of 2223")
	)
	(layers
		(0 "F.Cu" signal "TOP")
		(4 "In1.Cu" signal "L2GND")
		(6 "In2.Cu" signal "L3")
		(8 "In3.Cu" signal "L4GND")
		(10 "In4.Cu" signal "L5")
		(12 "In5.Cu" signal "L6VCC")
		(14 "In6.Cu" signal "L7VCC")
		(16 "In7.Cu" signal "L8")
		(18 "In8.Cu" signal "L9GND")
		(20 "In9.Cu" signal "L10")
		(22 "In10.Cu" signal "L11GND")
		(2 "B.Cu" signal "BOTTOM")
		(9 "F.Adhes" user "F.Adhesive")
		(11 "B.Adhes" user "B.Adhesive")
		(13 "F.Paste" user "Package Geometry/Pastemask Top")
		(15 "B.Paste" user "Package Geometry/Pastemask Bottom")
		(5 "F.SilkS" user "Ref Des/Silkscreen Top")
		(7 "B.SilkS" user "Ref Des/Silkscreen Bottom")
		(1 "F.Mask" user "Board Geometry/Soldermask Top")
		(3 "B.Mask" user "Board Geometry/Soldermask Bottom")
		(17 "Dwgs.User" user "User.Drawings")
		(19 "Cmts.User" user "User.Comments")
		(21 "Eco1.User" user "User.Eco1")
		(23 "Eco2.User" user "User.Eco2")
		(25 "Edge.Cuts" user "Board Geometry/Outline")
		(27 "Margin" user)
		(31 "F.CrtYd" user "Package Geometry/Place Bound Top")
		(29 "B.CrtYd" user "Package Geometry/Place Bound Bottom")
		(35 "F.Fab" user "Ref Des/Assembly Top")
		(33 "B.Fab" user "Ref Des/Assembly Bottom")
	)
	(footprint ""
		(layer "F.Cu")
		(at 20.684998 -170.285918 180)
		(property "Reference" "Q72"
			(at 0 0 180)
			(layer "F.SilkS")
			(hide yes)
			(effects
				(font
					(size 1.27 1.27)
				)
			)
		)
		(property "Value" "AO4406AL-GP"
			(at -3.707384 -1.5367 180)
			(unlocked yes)
			(layer "F.Fab")
			(hide yes)
			(effects
				(font
					(size 1.016 1.016)
					(thickness 0.1524)
				)
			)
		)
		(property "Device Type" "SOIC8H69"
			(at -3.707384 -3.0607 180)
			(unlocked yes)
			(layer "F.Fab")
			(hide yes)
			(effects
				(font
					(size 1.016 1.016)
					(thickness 0.1524)
				)
			)
		)
		(duplicate_pad_numbers_are_jumpers no)
		(fp_line
			(start 2.1336 1.4224)
			(end 2.1336 -1.4224)
			(stroke
				(width 0.1524)
				(type default)
			)
			(layer "F.SilkS")
		)
		(fp_line
			(start 2.1336 -1.4224)
			(end -2.7432 -1.4224)
			(stroke
				(width 0.1524)
				(type default)
			)
			(layer "F.SilkS")
		)
		(fp_line
			(start -2.1844 -0.0508)
			(end -2.7178 0.508)
			(stroke
				(width 0.1524)
				(type default)
			)
			(layer "F.SilkS")
		)
		(fp_line
			(start -2.6289 3.4417)
			(end -2.6289 1.4732)
			(stroke
				(width 0.381)
				(type default)
			)
			(layer "F.SilkS")
		)
		(fp_line
			(start -2.7178 -0.508)
			(end -2.1844 -0.0508)
			(stroke
				(width 0.1524)
				(type default)
			)
			(layer "F.SilkS")
		)
		(fp_line
			(start -2.7432 1.4224)
			(end 2.1336 1.4224)
			(stroke
				(width 0.1524)
				(type default)
			)
			(layer "F.SilkS")
		)
		(fp_line
			(start -2.7432 1.4224)
			(end -2.6416 1.4224)
			(stroke
				(width 0.1524)
				(type default)
			)
			(layer "F.SilkS")
		)
		(fp_line
			(start -2.7432 -1.4224)
			(end -2.7432 1.4224)
			(stroke
				(width 0.1524)
				(type default)
			)
			(layer "F.SilkS")
		)
		(fp_poly
			(pts
				(xy -2.2098 -1.4224) (xy -2.2098 1.4224) (xy 2.2098 1.4224) (xy 2.2098 -1.4224)
			)
			(stroke
				(width 0)
				(type default)
			)
			(fill yes)
			(layer "F.SilkS")
		)
		(fp_rect
			(start -2.450084 2.999994)
			(end 2.450084 -2.999994)
			(stroke
				(width 0)
				(type default)
			)
			(fill no)
			(layer "F.CrtYd")
		)
		(fp_poly
			(pts
				(xy -2.8194 3.6322) (xy -2.8194 -3.6322) (xy 2.8194 -3.6322) (xy 2.8194 1.18364) (xy 2.450084 1.18364)
				(xy 2.450084 -2.999994) (xy -2.450084 -2.999994) (xy -2.450084 2.999994) (xy 2.450084 2.999994)
				(xy 2.450084 1.18618) (xy 2.8194 1.18618) (xy 2.8194 3.6322)
			)
			(stroke
				(width 0)
				(type default)
			)
			(fill no)
			(layer "F.CrtYd")
		)
		(fp_rect
			(start -2.8194 3.6322)
			(end 2.8194 -3.6322)
			(stroke
				(width 0)
				(type default)
			)
			(fill no)
			(layer "F.Fab")
		)
		(pad "1" smd rect
			(at -1.905 2.54 180)
			(size 0.635 1.651)
			(layers "F.Cu" "F.Mask" "F.Paste")
			(net "P5V_HDD12")
		)
		(pad "2" smd rect
			(at -0.635 2.54 180)
			(size 0.635 1.651)
			(layers "F.Cu" "F.Mask" "F.Paste")
			(net "P5V_HDD12")
		)
		(pad "3" smd rect
			(at 0.635 2.54 180)
			(size 0.635 1.651)
			(layers "F.Cu" "F.Mask" "F.Paste")
			(net "P5V_HDD12")
		)
		(pad "4" smd rect
			(at 1.905 2.54 180)
			(size 0.635 1.651)
			(layers "F.Cu" "F.Mask" "F.Paste")
			(net "SW_HDD_P12")
		)
		(pad "5" smd rect
			(at 1.905 -2.54 180)
			(size 0.635 1.651)
			(layers "F.Cu" "F.Mask" "F.Paste")
			(net "P5V_A_1")
		)
		(pad "6" smd rect
			(at 0.635 -2.54 180)
			(size 0.635 1.651)
			(layers "F.Cu" "F.Mask" "F.Paste")
			(net "P5V_A_1")
		)
		(pad "7" smd rect
			(at -0.635 -2.54 180)
			(size 0.635 1.651)
			(layers "F.Cu" "F.Mask" "F.Paste")
			(net "P5V_A_1")
		)
		(pad "8" smd rect
			(at -1.905 -2.54 180)
			(size 0.635 1.651)
			(layers "F.Cu" "F.Mask" "F.Paste")
			(net "P5V_A_1")
		)
	)
	(footprint ""
		(layer "F.Cu")
		(at 473.514928 -127.254)
		(property "Reference" "R346"
			(at 0 0 0)
			(layer "F.SilkS")
			(hide yes)
			(effects
				(font
					(size 1.27 1.27)
				)
			)
		)
		(property "Value" "91R3F-1-GP"
			(at -0.0254 -2.5146 0)
			(unlocked yes)
			(layer "F.Fab")
			(hide yes)
			(effects
				(font
					(size 1.016 1.016)
					(thickness 0.1524)
				)
			)
		)
		(property "Device Type" "R603H22"
			(at -0.0254 -4.0386 0)
			(unlocked yes)
			(layer "F.Fab")
			(hide yes)
			(effects
				(font
					(size 1.016 1.016)
					(thickness 0.1524)
				)
			)
		)
		(duplicate_pad_numbers_are_jumpers no)
		(fp_line
			(start -0.4826 0)
			(end -0.2032 0)
			(stroke
				(width 0.2032)
				(type default)
			)
			(layer "F.SilkS")
		)
		(fp_line
			(start 0.2032 0)
			(end 0.4826 0)
			(stroke
				(width 0.2032)
				(type default)
			)
			(layer "F.SilkS")
		)
		(fp_rect
			(start -0.5842 1.3335)
			(end 0.5842 -1.3335)
			(stroke
				(width 0)
				(type default)
			)
			(fill no)
			(layer "F.CrtYd")
		)
		(fp_rect
			(start -0.5842 1.3335)
			(end 0.5842 -1.3335)
			(stroke
				(width 0)
				(type default)
			)
			(fill no)
			(layer "F.Fab")
		)
		(pad "1" smd custom
			(at 0 -0.762)
			(size 0.2159 0.2159)
			(layers "F.Cu" "F.Mask" "F.Paste")
			(net "P5V_A_4")
			(options
				(clearance outline)
				(anchor circle)
			)
			(primitives
				(gr_poly
					(pts
						(arc
							(start -0.3302 -0.4318)
							(mid -0.402042 -0.402042)
							(end -0.4318 -0.3302)
						)
						(arc
							(start -0.4318 0.3302)
							(mid -0.402042 0.402042)
							(end -0.3302 0.4318)
						)
						(arc
							(start 0.3302 0.4318)
							(mid 0.402042 0.402042)
							(end 0.4318 0.3302)
						)
						(arc
							(start 0.4318 -0.3302)
							(mid 0.402042 -0.402042)
							(end 0.3302 -0.4318)
						)
					)
					(width 0)
					(fill yes)
				)
			)
		)
		(pad "2" smd custom
			(at 0 0.762)
			(size 0.2159 0.2159)
			(layers "F.Cu" "F.Mask" "F.Paste")
			(net "DRV_ACT_23")
			(options
				(clearance outline)
				(anchor circle)
			)
			(primitives
				(gr_poly
					(pts
						(arc
							(start -0.3302 -0.4318)
							(mid -0.402042 -0.402042)
							(end -0.4318 -0.3302)
						)
						(arc
							(start -0.4318 0.3302)
							(mid -0.402042 0.402042)
							(end -0.3302 0.4318)
						)
						(arc
							(start 0.3302 0.4318)
							(mid 0.402042 0.402042)
							(end 0.4318 0.3302)
						)
						(arc
							(start 0.4318 -0.3302)
							(mid 0.402042 -0.402042)
							(end 0.3302 -0.4318)
						)
					)
					(width 0)
					(fill yes)
				)
			)
		)
	)
	(footprint ""
		(layer "F.Cu")
		(at 240.4618 -260.5532 180)
		(property "Reference" "R47"
			(at 0 0 180)
			(layer "F.SilkS")
			(hide yes)
			(effects
				(font
					(size 1.27 1.27)
				)
			)
		)
		(property "Value" "0R2J-2-GP"
			(at 0.064008 -3.993896 180)
			(unlocked yes)
			(layer "F.Fab")
			(hide yes)
			(effects
				(font
					(size 1.016 1.016)
					(thickness 0.1524)
				)
			)
		)
		(property "Device Type" "R402H16"
			(at 0.064008 -5.517896 180)
			(unlocked yes)
			(layer "F.Fab")
			(hide yes)
			(effects
				(font
					(size 1.016 1.016)
					(thickness 0.1524)
				)
			)
		)
		(duplicate_pad_numbers_are_jumpers no)
		(fp_line
			(start 0.508 -0.9398)
			(end -0.508 -0.9398)
			(stroke
				(width 0.1524)
				(type default)
			)
			(layer "F.SilkS")
		)
		(fp_line
			(start -0.508 -0.9398)
			(end -0.508 0.9398)
			(stroke
				(width 0.1524)
				(type default)
			)
			(layer "F.SilkS")
		)
		(fp_rect
			(start -0.508 0.9398)
			(end 0.508 -0.9398)
			(stroke
				(width 0)
				(type default)
			)
			(fill no)
			(layer "F.CrtYd")
		)
		(fp_rect
			(start -0.508 0.9398)
			(end 0.508 -0.9398)
			(stroke
				(width 0)
				(type default)
			)
			(fill no)
			(layer "F.Fab")
		)
		(pad "1" smd custom
			(at 0 -0.4445 180)
			(size 0.1397 0.1397)
			(layers "F.Cu" "F.Mask" "F.Paste")
			(net "IO_EXP5_SDA")
			(options
				(clearance outline)
				(anchor circle)
			)
			(primitives
				(gr_poly
					(pts
						(arc
							(start -0.1778 -0.2794)
							(mid -0.249642 -0.249642)
							(end -0.2794 -0.1778)
						)
						(arc
							(start -0.2794 0.1778)
							(mid -0.249642 0.249642)
							(end -0.1778 0.2794)
						)
						(arc
							(start 0.1778 0.2794)
							(mid 0.249642 0.249642)
							(end 0.2794 0.1778)
						)
						(arc
							(start 0.2794 -0.1778)
							(mid 0.249642 -0.249642)
							(end 0.1778 -0.2794)
						)
					)
					(width 0)
					(fill yes)
				)
			)
		)
		(pad "2" smd custom
			(at 0 0.4445 180)
			(size 0.1397 0.1397)
			(layers "F.Cu" "F.Mask" "F.Paste")
			(net "I2C_DRIVE_A_INS_SDA")
			(options
				(clearance outline)
				(anchor circle)
			)
			(primitives
				(gr_poly
					(pts
						(arc
							(start -0.1778 -0.2794)
							(mid -0.249642 -0.249642)
							(end -0.2794 -0.1778)
						)
						(arc
							(start -0.2794 0.1778)
							(mid -0.249642 0.249642)
							(end -0.1778 0.2794)
						)
						(arc
							(start 0.1778 0.2794)
							(mid 0.249642 0.249642)
							(end 0.2794 0.1778)
						)
						(arc
							(start 0.2794 -0.1778)
							(mid 0.249642 -0.249642)
							(end 0.1778 -0.2794)
						)
					)
					(width 0)
					(fill yes)
				)
			)
		)
	)
	(footprint ""
		(layer "F.Cu")
		(at 54.546246 -276.065742 -90)
		(property "Reference" "R161"
			(at 0 0 270)
			(layer "F.SilkS")
			(hide yes)
			(effects
				(font
					(size 1.27 1.27)
				)
			)
		)
		(property "Value" "1KR2F-3-GP"
			(at 0.064008 -3.993896 270)
			(unlocked yes)
			(layer "F.Fab")
			(hide yes)
			(effects
				(font
					(size 1.016 1.016)
					(thickness 0.1524)
				)
			)
		)
		(property "Device Type" "R402H16"
			(at 0.064008 -5.517896 270)
			(unlocked yes)
			(layer "F.Fab")
			(hide yes)
			(effects
				(font
					(size 1.016 1.016)
					(thickness 0.1524)
				)
			)
		)
		(duplicate_pad_numbers_are_jumpers no)
		(fp_line
			(start -0.508 -0.9398)
			(end -0.508 0.9398)
			(stroke
				(width 0.1524)
				(type default)
			)
			(layer "F.SilkS")
		)
		(fp_line
			(start 0.508 -0.9398)
			(end -0.508 -0.9398)
			(stroke
				(width 0.1524)
				(type default)
			)
			(layer "F.SilkS")
		)
		(fp_rect
			(start -0.508 0.9398)
			(end 0.508 -0.9398)
			(stroke
				(width 0)
				(type default)
			)
			(fill no)
			(layer "F.CrtYd")
		)
		(fp_rect
			(start -0.508 0.9398)
			(end 0.508 -0.9398)
			(stroke
				(width 0)
				(type default)
			)
			(fill no)
			(layer "F.Fab")
		)
		(pad "1" smd custom
			(at 0 -0.4445 270)
			(size 0.1397 0.1397)
			(layers "F.Cu" "F.Mask" "F.Paste")
			(net "P3V3_STBY_A")
			(options
				(clearance outline)
				(anchor circle)
			)
			(primitives
				(gr_poly
					(pts
						(arc
							(start -0.1778 -0.2794)
							(mid -0.249642 -0.249642)
							(end -0.2794 -0.1778)
						)
						(arc
							(start -0.2794 0.1778)
							(mid -0.249642 0.249642)
							(end -0.1778 0.2794)
						)
						(arc
							(start 0.1778 0.2794)
							(mid 0.249642 0.249642)
							(end 0.2794 0.1778)
						)
						(arc
							(start 0.2794 -0.1778)
							(mid 0.249642 -0.249642)
							(end 0.1778 -0.2794)
						)
					)
					(width 0)
					(fill yes)
				)
			)
		)
		(pad "2" smd custom
			(at 0 0.4445 270)
			(size 0.1397 0.1397)
			(layers "F.Cu" "F.Mask" "F.Paste")
			(net "SW_PWR_R_HDD1")
			(options
				(clearance outline)
				(anchor circle)
			)
			(primitives
				(gr_poly
					(pts
						(arc
							(start -0.1778 -0.2794)
							(mid -0.249642 -0.249642)
							(end -0.2794 -0.1778)
						)
						(arc
							(start -0.2794 0.1778)
							(mid -0.249642 0.249642)
							(end -0.1778 0.2794)
						)
						(arc
							(start 0.1778 0.2794)
							(mid 0.249642 0.249642)
							(end 0.2794 0.1778)
						)
						(arc
							(start 0.2794 -0.1778)
							(mid 0.249642 -0.249642)
							(end 0.1778 -0.2794)
						)
					)
					(width 0)
					(fill yes)
				)
			)
		)
	)
	(footprint ""
		(layer "F.Cu")
		(at 310.69534 -60.017914 -90)
		(property "Reference" "R396"
			(at 0 0 270)
			(layer "F.SilkS")
			(hide yes)
			(effects
				(font
					(size 1.27 1.27)
				)
			)
		)
		(property "Value" "10KR2F-2-GP"
			(at 0.064008 -3.993896 270)
			(unlocked yes)
			(layer "F.Fab")
			(hide yes)
			(effects
				(font
					(size 1.016 1.016)
					(thickness 0.1524)
				)
			)
		)
		(property "Device Type" "R402H16"
			(at 0.064008 -5.517896 270)
			(unlocked yes)
			(layer "F.Fab")
			(hide yes)
			(effects
				(font
					(size 1.016 1.016)
					(thickness 0.1524)
				)
			)
		)
		(duplicate_pad_numbers_are_jumpers no)
		(fp_line
			(start -0.508 -0.9398)
			(end -0.508 0.9398)
			(stroke
				(width 0.1524)
				(type default)
			)
			(layer "F.SilkS")
		)
		(fp_line
			(start 0.508 -0.9398)
			(end -0.508 -0.9398)
			(stroke
				(width 0.1524)
				(type default)
			)
			(layer "F.SilkS")
		)
		(fp_rect
			(start -0.508 0.9398)
			(end 0.508 -0.9398)
			(stroke
				(width 0)
				(type default)
			)
			(fill no)
			(layer "F.CrtYd")
		)
		(fp_rect
			(start -0.508 0.9398)
			(end 0.508 -0.9398)
			(stroke
				(width 0)
				(type default)
			)
			(fill no)
			(layer "F.Fab")
		)
		(pad "1" smd custom
			(at 0 -0.4445 270)
			(size 0.1397 0.1397)
			(layers "F.Cu" "F.Mask" "F.Paste")
			(net "SYS_B_RESET_BUFFER_N")
			(options
				(clearance outline)
				(anchor circle)
			)
			(primitives
				(gr_poly
					(pts
						(arc
							(start -0.1778 -0.2794)
							(mid -0.249642 -0.249642)
							(end -0.2794 -0.1778)
						)
						(arc
							(start -0.2794 0.1778)
							(mid -0.249642 0.249642)
							(end -0.1778 0.2794)
						)
						(arc
							(start 0.1778 0.2794)
							(mid 0.249642 0.249642)
							(end 0.2794 0.1778)
						)
						(arc
							(start 0.2794 -0.1778)
							(mid 0.249642 -0.249642)
							(end 0.1778 -0.2794)
						)
					)
					(width 0)
					(fill yes)
				)
			)
		)
		(pad "2" smd custom
			(at 0 0.4445 270)
			(size 0.1397 0.1397)
			(layers "F.Cu" "F.Mask" "F.Paste")
			(net "GND")
			(options
				(clearance outline)
				(anchor circle)
			)
			(primitives
				(gr_poly
					(pts
						(arc
							(start -0.1778 -0.2794)
							(mid -0.249642 -0.249642)
							(end -0.2794 -0.1778)
						)
						(arc
							(start -0.2794 0.1778)
							(mid -0.249642 0.249642)
							(end -0.1778 0.2794)
						)
						(arc
							(start 0.1778 0.2794)
							(mid 0.249642 0.249642)
							(end 0.2794 0.1778)
						)
						(arc
							(start 0.2794 -0.1778)
							(mid 0.249642 -0.249642)
							(end 0.1778 -0.2794)
						)
					)
					(width 0)
					(fill yes)
				)
			)
		)
	)
	(footprint ""
		(layer "F.Cu")
		(at 398.88795 -275.760942 180)
		(property "Reference" "R331"
			(at 0 0 180)
			(layer "F.SilkS")
			(hide yes)
			(effects
				(font
					(size 1.27 1.27)
				)
			)
		)
		(property "Value" "0R2J-2-GP"
			(at 0.064008 -3.993896 180)
			(unlocked yes)
			(layer "F.Fab")
			(hide yes)
			(effects
				(font
					(size 1.016 1.016)
					(thickness 0.1524)
				)
			)
		)
		(property "Device Type" "R402H16"
			(at 0.064008 -5.517896 180)
			(unlocked yes)
			(layer "F.Fab")
			(hide yes)
			(effects
				(font
					(size 1.016 1.016)
					(thickness 0.1524)
				)
			)
		)
		(duplicate_pad_numbers_are_jumpers no)
		(fp_line
			(start 0.508 -0.9398)
			(end -0.508 -0.9398)
			(stroke
				(width 0.1524)
				(type default)
			)
			(layer "F.SilkS")
		)
		(fp_line
			(start -0.508 -0.9398)
			(end -0.508 0.9398)
			(stroke
				(width 0.1524)
				(type default)
			)
			(layer "F.SilkS")
		)
		(fp_rect
			(start -0.508 0.9398)
			(end 0.508 -0.9398)
			(stroke
				(width 0)
				(type default)
			)
			(fill no)
			(layer "F.CrtYd")
		)
		(fp_rect
			(start -0.508 0.9398)
			(end 0.508 -0.9398)
			(stroke
				(width 0)
				(type default)
			)
			(fill no)
			(layer "F.Fab")
		)
		(pad "1" smd custom
			(at 0 -0.4445 180)
			(size 0.1397 0.1397)
			(layers "F.Cu" "F.Mask" "F.Paste")
			(net "SW_HDD_G8")
			(options
				(clearance outline)
				(anchor circle)
			)
			(primitives
				(gr_poly
					(pts
						(arc
							(start -0.1778 -0.2794)
							(mid -0.249642 -0.249642)
							(end -0.2794 -0.1778)
						)
						(arc
							(start -0.2794 0.1778)
							(mid -0.249642 0.249642)
							(end -0.1778 0.2794)
						)
						(arc
							(start 0.1778 0.2794)
							(mid 0.249642 0.249642)
							(end 0.2794 0.1778)
						)
						(arc
							(start 0.2794 -0.1778)
							(mid 0.249642 -0.249642)
							(end 0.1778 -0.2794)
						)
					)
					(width 0)
					(fill yes)
				)
			)
		)
		(pad "2" smd custom
			(at 0 0.4445 180)
			(size 0.1397 0.1397)
			(layers "F.Cu" "F.Mask" "F.Paste")
			(net "SW_HDD_R8")
			(options
				(clearance outline)
				(anchor circle)
			)
			(primitives
				(gr_poly
					(pts
						(arc
							(start -0.1778 -0.2794)
							(mid -0.249642 -0.249642)
							(end -0.2794 -0.1778)
						)
						(arc
							(start -0.2794 0.1778)
							(mid -0.249642 0.249642)
							(end -0.1778 0.2794)
						)
						(arc
							(start 0.1778 0.2794)
							(mid 0.249642 0.249642)
							(end 0.2794 0.1778)
						)
						(arc
							(start 0.2794 -0.1778)
							(mid 0.249642 -0.249642)
							(end 0.1778 -0.2794)
						)
					)
					(width 0)
					(fill yes)
				)
			)
		)
	)
	(footprint ""
		(layer "F.Cu")
		(at 457.699872 -188.999876 180)
		(property "Reference" "C330"
			(at 0 0 180)
			(layer "F.SilkS")
			(hide yes)
			(effects
				(font
					(size 1.27 1.27)
				)
			)
		)
		(property "Value" "SC4D7U25V5KX-1-GP"
			(at -0.0762 -6.1214 180)
			(unlocked yes)
			(layer "F.Fab")
			(hide yes)
			(effects
				(font
					(size 1.016 1.016)
					(thickness 0.1524)
				)
			)
		)
		(property "Device Type" "C805H58"
			(at -0.0762 -8.1534 180)
			(unlocked yes)
			(layer "F.Fab")
			(hide yes)
			(effects
				(font
					(size 1.016 1.016)
					(thickness 0.1524)
				)
			)
		)
		(duplicate_pad_numbers_are_jumpers no)
		(fp_line
			(start 0.635 0)
			(end -0.635 0)
			(stroke
				(width 0.508)
				(type default)
			)
			(layer "F.SilkS")
		)
		(fp_rect
			(start -0.9652 1.778)
			(end 0.9652 -1.778)
			(stroke
				(width 0)
				(type default)
			)
			(fill no)
			(layer "F.CrtYd")
		)
		(fp_poly
			(pts
				(xy -0.9652 -1.778) (xy 0.9652 -1.778) (xy 0.9652 1.778) (xy -0.9652 1.778)
			)
			(stroke
				(width 0)
				(type default)
			)
			(fill no)
			(layer "F.Fab")
		)
		(pad "1" smd rect
			(at 0 -0.9652 180)
			(size 1.397 1.143)
			(layers "F.Cu" "F.Mask" "F.Paste")
			(net "P12V_HDD22")
		)
		(pad "2" smd rect
			(at 0 0.9652 180)
			(size 1.397 1.143)
			(layers "F.Cu" "F.Mask" "F.Paste")
			(net "GND")
		)
	)
)
